# S9S_MB_2U (Grand Teton) — schematic netlist excerpt (pin names and nets, part order shuffled) for the footprints in the layout excerpt that follows; sources: Cadence DE-HDL packaged netlist, KiCad conversion of 03242023_DA0F0TMBIJ0_F0T_Motherboard_J_brd_V01_OCP.brd

C706  Q_CAP_DIFFBUS  DIFF BUS_0.22UF 6.3V 20% X6S  pkg C0201  page 177 : \1\ = P5E_CPU1_PE4_TX_C_DN<1> ; \2\ = P5E_CPU1_PE4_TX_DN<1>
C2051  Q_CAP  0.1UF 25V 10% X7R  pkg 0402  page 250 : A = P3V3_ADC128_VCC ; B = GND

U58  74LVC2G07DW7  74LVC2G07DW-7 IC  pkg SOT363_0-65_2X1-25XC  page 162
  \1a\  = OCP_V3_2_PRSNT0_R_N
  GND  = GND
  \2a\  = OCP_V3_2_PRSNT1_R_N
  \2y\  = HP_LVC3_OCP_V3_2_PRSNT2_N_R
  VCC  = P3V3_AUX
  \1y\  = HP_LVC3_OCP_V3_2_PRSNT2_N_R

(kicad_pcb
	(version 20260206)
	(generator "pcbnew")
	(generator_version "10.0")
	(general
		(thickness 1.6)
		(legacy_teardrops no)
	)
	(paper "A4")
	(title_block
		(title "03242023_DA0F0TMBIJ0_F0T_Motherboard_J_brd_V01_OCP.brd")
		(comment 1 "Grand Teton / footprints 3589-3591 of 6105")
	)
	(layers
		(0 "F.Cu" signal "TOP")
		(4 "In1.Cu" signal "GND")
		(6 "In2.Cu" signal "IN1")
		(8 "In3.Cu" signal "GND1")
		(10 "In4.Cu" signal "IN2")
		(12 "In5.Cu" signal "GND2")
		(14 "In6.Cu" signal "IN3")
		(16 "In7.Cu" signal "GND3")
		(18 "In8.Cu" signal "VCC")
		(20 "In9.Cu" signal "VCC1")
		(22 "In10.Cu" signal "GND4")
		(24 "In11.Cu" signal "IN4")
		(26 "In12.Cu" signal "GND5")
		(28 "In13.Cu" signal "IN5")
		(30 "In14.Cu" signal "GND6")
		(32 "In15.Cu" signal "IN6")
		(34 "In16.Cu" signal "GND7")
		(2 "B.Cu" signal "BOTTOM")
		(9 "F.Adhes" user "F.Adhesive")
		(11 "B.Adhes" user "B.Adhesive")
		(13 "F.Paste" user "Package Geometry/Pastemask Top")
		(15 "B.Paste" user "Package Geometry/Pastemask Bottom")
		(5 "F.SilkS" user "Ref Des/Silkscreen Top")
		(7 "B.SilkS" user "Ref Des/Silkscreen Bottom")
		(1 "F.Mask" user "Board Geometry/Soldermask Top")
		(3 "B.Mask" user "Board Geometry/Soldermask Bottom")
		(17 "Dwgs.User" user "User.Drawings")
		(19 "Cmts.User" user "User.Comments")
		(21 "Eco1.User" user "User.Eco1")
		(23 "Eco2.User" user "User.Eco2")
		(25 "Edge.Cuts" user "Board Geometry/Outline")
		(27 "Margin" user)
		(31 "F.CrtYd" user "Package Geometry/Place Bound Top")
		(29 "B.CrtYd" user "Package Geometry/Place Bound Bottom")
		(35 "F.Fab" user "Ref Des/Assembly Top")
		(33 "B.Fab" user "Ref Des/Assembly Bottom")
	)
	(footprint ""
		(layer "F.Cu")
		(at 24.67356 -76.266548)
		(property "Reference" "U58"
			(at -1.1938 -2.02057 0)
			(unlocked yes)
			(layer "F.SilkS")
			(effects
				(font
					(size 0.7874 0.5842)
					(thickness 0.1524)
				)
				(justify left)
			)
		)
		(property "Value" ""
			(at 0 0 0)
			(layer "F.Fab")
			(effects
				(font
					(size 1.27 1.27)
				)
			)
		)
		(duplicate_pad_numbers_are_jumpers no)
		(fp_line
			(start -1.38176 -1.100074)
			(end -1.38176 1.100074)
			(stroke
				(width 0.1524)
				(type default)
			)
			(layer "F.SilkS")
		)
		(fp_line
			(start -1.38176 1.100074)
			(end 1.38176 1.100074)
			(stroke
				(width 0.1524)
				(type default)
			)
			(layer "F.SilkS")
		)
		(fp_line
			(start -0.592074 -1.100074)
			(end -1.38176 -1.100074)
			(stroke
				(width 0.1524)
				(type default)
			)
			(layer "F.SilkS")
		)
		(fp_line
			(start 0 -0.508)
			(end -0.592074 -1.100074)
			(stroke
				(width 0.1524)
				(type default)
			)
			(layer "F.SilkS")
		)
		(fp_line
			(start 0.592074 -1.100074)
			(end 0 -0.508)
			(stroke
				(width 0.1524)
				(type default)
			)
			(layer "F.SilkS")
		)
		(fp_line
			(start 1.38176 -1.100074)
			(end 0.592074 -1.100074)
			(stroke
				(width 0.1524)
				(type default)
			)
			(layer "F.SilkS")
		)
		(fp_line
			(start 1.38176 1.100074)
			(end 1.38176 -1.100074)
			(stroke
				(width 0.1524)
				(type default)
			)
			(layer "F.SilkS")
		)
		(fp_poly
			(pts
				(xy -1.50241 -0.649986) (xy -1.9431 -0.429768) (xy -1.9431 -0.870204)
			)
			(stroke
				(width 0)
				(type default)
			)
			(fill yes)
			(layer "F.SilkS")
		)
		(fp_line
			(start -0.674878 -1.100074)
			(end -0.674878 1.100074)
			(stroke
				(width 0.1)
				(type default)
			)
			(layer "F.Fab")
		)
		(fp_line
			(start -0.674878 1.100074)
			(end 0.674878 1.100074)
			(stroke
				(width 0.1)
				(type default)
			)
			(layer "F.Fab")
		)
		(fp_line
			(start 0.674878 -1.100074)
			(end -0.674878 -1.100074)
			(stroke
				(width 0.1)
				(type default)
			)
			(layer "F.Fab")
		)
		(fp_line
			(start 0.674878 1.100074)
			(end 0.674878 -1.100074)
			(stroke
				(width 0.1)
				(type default)
			)
			(layer "F.Fab")
		)
		(fp_poly
			(pts
				(xy -1.9431 -0.870204) (xy -1.50241 -0.649986) (xy -1.9431 -0.429768)
			)
			(stroke
				(width 0)
				(type default)
			)
			(fill yes)
			(layer "F.Fab")
		)
		(pad "1" smd rect
			(at -0.94996 -0.649986 270)
			(size 0.4318 0.6096)
			(layers "F.Cu" "F.Mask" "F.Paste")
			(net "OCP_V3_2_PRSNT0_R_N")
		)
		(pad "2" smd rect
			(at -0.94996 0 270)
			(size 0.4318 0.6096)
			(layers "F.Cu" "F.Mask" "F.Paste")
			(net "GND")
		)
		(pad "3" smd rect
			(at -0.94996 0.649986 270)
			(size 0.4318 0.6096)
			(layers "F.Cu" "F.Mask" "F.Paste")
			(net "OCP_V3_2_PRSNT1_R_N")
		)
		(pad "4" smd rect
			(at 0.94996 0.649986 270)
			(size 0.4318 0.6096)
			(layers "F.Cu" "F.Mask" "F.Paste")
			(net "HP_LVC3_OCP_V3_2_PRSNT2_N_R")
		)
		(pad "5" smd rect
			(at 0.94996 0 270)
			(size 0.4318 0.6096)
			(layers "F.Cu" "F.Mask" "F.Paste")
			(net "P3V3_AUX")
		)
		(pad "6" smd rect
			(at 0.94996 -0.649986 270)
			(size 0.4318 0.6096)
			(layers "F.Cu" "F.Mask" "F.Paste")
			(net "HP_LVC3_OCP_V3_2_PRSNT2_N_R")
		)
	)
	(footprint ""
		(layer "F.Cu")
		(at 20.190714 -110.875826 180)
		(property "Reference" "C2051"
			(at 0 0 180)
			(layer "F.SilkS")
			(hide yes)
			(effects
				(font
					(size 1.27 1.27)
				)
			)
		)
		(property "Value" ""
			(at 0 0 180)
			(layer "F.Fab")
			(effects
				(font
					(size 1.27 1.27)
				)
			)
		)
		(duplicate_pad_numbers_are_jumpers no)
		(fp_line
			(start 0.7874 0.4064)
			(end -0.7874 0.4064)
			(stroke
				(width 0.1524)
				(type default)
			)
			(layer "F.SilkS")
		)
		(fp_line
			(start 0.7874 -0.4064)
			(end 0.7874 0.4064)
			(stroke
				(width 0.1524)
				(type default)
			)
			(layer "F.SilkS")
		)
		(fp_line
			(start -0.7874 0.4064)
			(end -0.7874 -0.4064)
			(stroke
				(width 0.1524)
				(type default)
			)
			(layer "F.SilkS")
		)
		(fp_line
			(start -0.7874 -0.4064)
			(end 0.7874 -0.4064)
			(stroke
				(width 0.1524)
				(type default)
			)
			(layer "F.SilkS")
		)
		(fp_line
			(start 0.67945 0.3048)
			(end 0.120396 0.3048)
			(stroke
				(width 0.1)
				(type default)
			)
			(layer "F.Fab")
		)
		(fp_line
			(start 0.67945 -0.3048)
			(end 0.67945 0.3048)
			(stroke
				(width 0.1)
				(type default)
			)
			(layer "F.Fab")
		)
		(fp_line
			(start 0.12065 -0.2794)
			(end 0.12065 -0.3048)
			(stroke
				(width 0.1)
				(type default)
			)
			(layer "F.Fab")
		)
		(fp_line
			(start 0.12065 -0.3048)
			(end 0.67945 -0.3048)
			(stroke
				(width 0.1)
				(type default)
			)
			(layer "F.Fab")
		)
		(fp_line
			(start 0.120396 0.3048)
			(end 0.120396 0.2794)
			(stroke
				(width 0.1)
				(type default)
			)
			(layer "F.Fab")
		)
		(fp_line
			(start 0.120396 0.2794)
			(end -0.12065 0.2794)
			(stroke
				(width 0.1)
				(type default)
			)
			(layer "F.Fab")
		)
		(fp_line
			(start -0.12065 0.3048)
			(end -0.67945 0.3048)
			(stroke
				(width 0.1)
				(type default)
			)
			(layer "F.Fab")
		)
		(fp_line
			(start -0.12065 0.2794)
			(end -0.12065 0.3048)
			(stroke
				(width 0.1)
				(type default)
			)
			(layer "F.Fab")
		)
		(fp_line
			(start -0.12065 -0.2794)
			(end 0.12065 -0.2794)
			(stroke
				(width 0.1)
				(type default)
			)
			(layer "F.Fab")
		)
		(fp_line
			(start -0.12065 -0.305054)
			(end -0.12065 -0.2794)
			(stroke
				(width 0.1)
				(type default)
			)
			(layer "F.Fab")
		)
		(fp_line
			(start -0.67945 0.3048)
			(end -0.67945 -0.305054)
			(stroke
				(width 0.1)
				(type default)
			)
			(layer "F.Fab")
		)
		(fp_line
			(start -0.67945 -0.305054)
			(end -0.12065 -0.305054)
			(stroke
				(width 0.1)
				(type default)
			)
			(layer "F.Fab")
		)
		(pad "1" smd circle
			(at -0.40005 0 180)
			(size 0 0)
			(layers "F.Cu" "F.Mask" "F.Paste")
			(net "P3V3_ADC128_VCC")
		)
		(pad "2" smd circle
			(at 0.40005 0 180)
			(size 0 0)
			(layers "F.Cu" "F.Mask" "F.Paste")
			(net "GND")
		)
	)
	(footprint ""
		(layer "F.Cu")
		(at 53.278278 -408.517344 -90)
		(property "Reference" "C706"
			(at 0 0 270)
			(layer "F.SilkS")
			(hide yes)
			(effects
				(font
					(size 1.27 1.27)
				)
			)
		)
		(property "Value" ""
			(at 0 0 270)
			(layer "F.Fab")
			(effects
				(font
					(size 1.27 1.27)
				)
			)
		)
		(duplicate_pad_numbers_are_jumpers no)
		(fp_line
			(start -0.299974 0.150114)
			(end -0.299974 -0.150114)
			(stroke
				(width 0.1)
				(type default)
			)
			(layer "F.Fab")
		)
		(fp_line
			(start 0.299974 0.150114)
			(end -0.299974 0.150114)
			(stroke
				(width 0.1)
				(type default)
			)
			(layer "F.Fab")
		)
		(fp_line
			(start -0.299974 -0.150114)
			(end 0.299974 -0.150114)
			(stroke
				(width 0.1)
				(type default)
			)
			(layer "F.Fab")
		)
		(fp_line
			(start 0.299974 -0.150114)
			(end 0.299974 0.150114)
			(stroke
				(width 0.1)
				(type default)
			)
			(layer "F.Fab")
		)
		(pad "1" smd rect
			(at -0.2667 0 270)
			(size 0.3048 0.381)
			(layers "F.Cu" "F.Mask" "F.Paste")
			(net "P5E_CPU1_PE4_TX_C_DN<1>")
		)
		(pad "2" smd rect
			(at 0.2667 0 270)
			(size 0.3048 0.381)
			(layers "F.Cu" "F.Mask" "F.Paste")
			(net "P5E_CPU1_PE4_TX_DN<1>")
		)
	)
)
